(kicad_pcb
	(version 20260206)
	(generator "pcbnew")
	(generator_version "10.0")
	(general
		(thickness 1.6)
		(legacy_teardrops no)
	)
	(paper "A4")
	(title_block
		(title "01162023_DA0F0TEBIF0_F0T_Expander_BD_F_brd_V02_OCP.brd")
		(comment 1 "Grand Teton / footprints 59-64 of 9728")
	)
	(layers
		(0 "F.Cu" signal "TOP")
		(4 "In1.Cu" signal "GND")
		(6 "In2.Cu" signal "VCC")
		(8 "In3.Cu" signal "VCC1")
		(10 "In4.Cu" signal "GND1")
		(12 "In5.Cu" signal "IN1")
		(14 "In6.Cu" signal "GND2")
		(16 "In7.Cu" signal "IN2")
		(18 "In8.Cu" signal "GND3")
		(20 "In9.Cu" signal "IN3")
		(22 "In10.Cu" signal "GND4")
		(24 "In11.Cu" signal "IN4")
		(26 "In12.Cu" signal "GND5")
		(28 "In13.Cu" signal "IN5")
		(30 "In14.Cu" signal "GND6")
		(32 "In15.Cu" signal "IN6")
		(34 "In16.Cu" signal "GND7")
		(2 "B.Cu" signal "BOTTOM")
		(9 "F.Adhes" user "F.Adhesive")
		(11 "B.Adhes" user "B.Adhesive")
		(13 "F.Paste" user "Package Geometry/Pastemask Top")
		(15 "B.Paste" user "Package Geometry/Pastemask Bottom")
		(5 "F.SilkS" user "Ref Des/Silkscreen Top")
		(7 "B.SilkS" user "Ref Des/Silkscreen Bottom")
		(1 "F.Mask" user "Board Geometry/Soldermask Top")
		(3 "B.Mask" user "Board Geometry/Soldermask Bottom")
		(17 "Dwgs.User" user "User.Drawings")
		(19 "Cmts.User" user "User.Comments")
		(21 "Eco1.User" user "User.Eco1")
		(23 "Eco2.User" user "User.Eco2")
		(25 "Edge.Cuts" user "Board Geometry/Outline")
		(27 "Margin" user)
		(31 "F.CrtYd" user "Package Geometry/Place Bound Top")
		(29 "B.CrtYd" user "Package Geometry/Place Bound Bottom")
		(35 "F.Fab" user "Ref Des/Assembly Top")
		(33 "B.Fab" user "Ref Des/Assembly Bottom")
	)
	(footprint ""
		(layer "F.Cu")
		(at 378.852684 -84.2518)
		(property "Reference" "R1773"
			(at 0 0 0)
			(layer "F.SilkS")
			(hide yes)
			(effects
				(font
					(size 1.27 1.27)
				)
			)
		)
		(property "Value" ""
			(at 0 0 0)
			(layer "F.Fab")
			(effects
				(font
					(size 1.27 1.27)
				)
			)
		)
		(duplicate_pad_numbers_are_jumpers no)
		(fp_line
			(start -0.7874 -0.4064)
			(end 0.7874 -0.4064)
			(stroke
				(width 0.1524)
				(type default)
			)
			(layer "F.SilkS")
		)
		(fp_line
			(start -0.7874 0.4064)
			(end -0.7874 -0.4064)
			(stroke
				(width 0.1524)
				(type default)
			)
			(layer "F.SilkS")
		)
		(fp_line
			(start 0.7874 -0.4064)
			(end 0.7874 0.4064)
			(stroke
				(width 0.1524)
				(type default)
			)
			(layer "F.SilkS")
		)
		(fp_line
			(start 0.7874 0.4064)
			(end -0.7874 0.4064)
			(stroke
				(width 0.1524)
				(type default)
			)
			(layer "F.SilkS")
		)
		(fp_line
			(start -0.67945 -0.305054)
			(end -0.12065 -0.305054)
			(stroke
				(width 0.1)
				(type default)
			)
			(layer "F.Fab")
		)
		(fp_line
			(start -0.67945 0.3048)
			(end -0.67945 -0.305054)
			(stroke
				(width 0.1)
				(type default)
			)
			(layer "F.Fab")
		)
		(fp_line
			(start -0.12065 -0.305054)
			(end -0.12065 -0.2794)
			(stroke
				(width 0.1)
				(type default)
			)
			(layer "F.Fab")
		)
		(fp_line
			(start -0.12065 -0.2794)
			(end 0.12065 -0.2794)
			(stroke
				(width 0.1)
				(type default)
			)
			(layer "F.Fab")
		)
		(fp_line
			(start -0.12065 0.2794)
			(end -0.12065 0.3048)
			(stroke
				(width 0.1)
				(type default)
			)
			(layer "F.Fab")
		)
		(fp_line
			(start -0.12065 0.3048)
			(end -0.67945 0.3048)
			(stroke
				(width 0.1)
				(type default)
			)
			(layer "F.Fab")
		)
		(fp_line
			(start 0.120396 0.2794)
			(end -0.12065 0.2794)
			(stroke
				(width 0.1)
				(type default)
			)
			(layer "F.Fab")
		)
		(fp_line
			(start 0.120396 0.3048)
			(end 0.120396 0.2794)
			(stroke
				(width 0.1)
				(type default)
			)
			(layer "F.Fab")
		)
		(fp_line
			(start 0.12065 -0.3048)
			(end 0.67945 -0.3048)
			(stroke
				(width 0.1)
				(type default)
			)
			(layer "F.Fab")
		)
		(fp_line
			(start 0.12065 -0.2794)
			(end 0.12065 -0.3048)
			(stroke
				(width 0.1)
				(type default)
			)
			(layer "F.Fab")
		)
		(fp_line
			(start 0.67945 -0.3048)
			(end 0.67945 0.3048)
			(stroke
				(width 0.1)
				(type default)
			)
			(layer "F.Fab")
		)
		(fp_line
			(start 0.67945 0.3048)
			(end 0.120396 0.3048)
			(stroke
				(width 0.1)
				(type default)
			)
			(layer "F.Fab")
		)
		(pad "1" smd circle
			(at -0.40005 0)
			(size 0 0)
			(layers "F.Cu" "F.Mask" "F.Paste")
			(net "SMB_BIC_I2C6_MUX_THERMAL_R_SDA")
		)
		(pad "2" smd circle
			(at 0.40005 0)
			(size 0 0)
			(layers "F.Cu" "F.Mask" "F.Paste")
			(net "SMB_BIC_I2C6_MUX_THERMAL_SDA")
		)
	)
	(footprint ""
		(layer "F.Cu")
		(at 135.598662 -66.32194 -90)
		(property "Reference" "PC840"
			(at 0 0 270)
			(layer "F.SilkS")
			(hide yes)
			(effects
				(font
					(size 1.27 1.27)
				)
			)
		)
		(property "Value" ""
			(at 0 0 270)
			(layer "F.Fab")
			(effects
				(font
					(size 1.27 1.27)
				)
			)
		)
		(duplicate_pad_numbers_are_jumpers no)
		(fp_line
			(start -0.7874 0.4064)
			(end -0.7874 -0.4064)
			(stroke
				(width 0.1524)
				(type default)
			)
			(layer "F.SilkS")
		)
		(fp_line
			(start 0.7874 0.4064)
			(end -0.7874 0.4064)
			(stroke
				(width 0.1524)
				(type default)
			)
			(layer "F.SilkS")
		)
		(fp_line
			(start -0.7874 -0.4064)
			(end 0.7874 -0.4064)
			(stroke
				(width 0.1524)
				(type default)
			)
			(layer "F.SilkS")
		)
		(fp_line
			(start 0.7874 -0.4064)
			(end 0.7874 0.4064)
			(stroke
				(width 0.1524)
				(type default)
			)
			(layer "F.SilkS")
		)
		(fp_line
			(start -0.67945 0.3048)
			(end -0.67945 -0.305054)
			(stroke
				(width 0.1)
				(type default)
			)
			(layer "F.Fab")
		)
		(fp_line
			(start -0.12065 0.3048)
			(end -0.67945 0.3048)
			(stroke
				(width 0.1)
				(type default)
			)
			(layer "F.Fab")
		)
		(fp_line
			(start 0.120396 0.3048)
			(end 0.120396 0.2794)
			(stroke
				(width 0.1)
				(type default)
			)
			(layer "F.Fab")
		)
		(fp_line
			(start 0.67945 0.3048)
			(end 0.120396 0.3048)
			(stroke
				(width 0.1)
				(type default)
			)
			(layer "F.Fab")
		)
		(fp_line
			(start -0.12065 0.2794)
			(end -0.12065 0.3048)
			(stroke
				(width 0.1)
				(type default)
			)
			(layer "F.Fab")
		)
		(fp_line
			(start 0.120396 0.2794)
			(end -0.12065 0.2794)
			(stroke
				(width 0.1)
				(type default)
			)
			(layer "F.Fab")
		)
		(fp_line
			(start -0.12065 -0.2794)
			(end 0.12065 -0.2794)
			(stroke
				(width 0.1)
				(type default)
			)
			(layer "F.Fab")
		)
		(fp_line
			(start 0.12065 -0.2794)
			(end 0.12065 -0.3048)
			(stroke
				(width 0.1)
				(type default)
			)
			(layer "F.Fab")
		)
		(fp_line
			(start 0.12065 -0.3048)
			(end 0.67945 -0.3048)
			(stroke
				(width 0.1)
				(type default)
			)
			(layer "F.Fab")
		)
		(fp_line
			(start 0.67945 -0.3048)
			(end 0.67945 0.3048)
			(stroke
				(width 0.1)
				(type default)
			)
			(layer "F.Fab")
		)
		(fp_line
			(start -0.67945 -0.305054)
			(end -0.12065 -0.305054)
			(stroke
				(width 0.1)
				(type default)
			)
			(layer "F.Fab")
		)
		(fp_line
			(start -0.12065 -0.305054)
			(end -0.12065 -0.2794)
			(stroke
				(width 0.1)
				(type default)
			)
			(layer "F.Fab")
		)
		(pad "1" smd circle
			(at -0.40005 0 270)
			(size 0 0)
			(layers "F.Cu" "F.Mask" "F.Paste")
			(net "P12V_SSD4_CO_GATE")
		)
		(pad "2" smd circle
			(at 0.40005 0 270)
			(size 0 0)
			(layers "F.Cu" "F.Mask" "F.Paste")
			(net "GND")
		)
	)
	(footprint ""
		(layer "F.Cu")
		(at 358.830626 -146.099276 180)
		(property "Reference" "PC822"
			(at 0 0 180)
			(layer "F.SilkS")
			(hide yes)
			(effects
				(font
					(size 1.27 1.27)
				)
			)
		)
		(property "Value" ""
			(at 0 0 180)
			(layer "F.Fab")
			(effects
				(font
					(size 1.27 1.27)
				)
			)
		)
		(duplicate_pad_numbers_are_jumpers no)
		(fp_line
			(start 1.524 0.762)
			(end -1.524 0.762)
			(stroke
				(width 0.1524)
				(type default)
			)
			(layer "F.SilkS")
		)
		(fp_line
			(start 1.524 -0.762)
			(end 1.524 0.762)
			(stroke
				(width 0.1524)
				(type default)
			)
			(layer "F.SilkS")
		)
		(fp_line
			(start -1.524 0.762)
			(end -1.524 -0.762)
			(stroke
				(width 0.1524)
				(type default)
			)
			(layer "F.SilkS")
		)
		(fp_line
			(start -1.524 -0.762)
			(end 1.524 -0.762)
			(stroke
				(width 0.1524)
				(type default)
			)
			(layer "F.SilkS")
		)
		(fp_line
			(start 1.1049 0.724916)
			(end 1.1049 -0.724916)
			(stroke
				(width 0.1)
				(type default)
			)
			(layer "F.Fab")
		)
		(fp_line
			(start 1.1049 -0.724916)
			(end -1.1049 -0.724916)
			(stroke
				(width 0.1)
				(type default)
			)
			(layer "F.Fab")
		)
		(fp_line
			(start -1.1049 0.724916)
			(end 1.1049 0.724916)
			(stroke
				(width 0.1)
				(type default)
			)
			(layer "F.Fab")
		)
		(fp_line
			(start -1.1049 -0.724916)
			(end -1.1049 0.724916)
			(stroke
				(width 0.1)
				(type default)
			)
			(layer "F.Fab")
		)
		(pad "1" smd rect
			(at -0.889 0)
			(size 1.016 1.27)
			(layers "F.Cu" "F.Mask" "F.Paste")
			(net "P12V_NIC6_R")
		)
		(pad "2" smd rect
			(at 0.889 0)
			(size 1.016 1.27)
			(layers "F.Cu" "F.Mask" "F.Paste")
			(net "GND")
		)
	)
	(footprint ""
		(layer "F.Cu")
		(at 334.583278 -49.94148)
		(property "Reference" "R5903"
			(at 0 0 0)
			(layer "F.SilkS")
			(hide yes)
			(effects
				(font
					(size 1.27 1.27)
				)
			)
		)
		(property "Value" ""
			(at 0 0 0)
			(layer "F.Fab")
			(effects
				(font
					(size 1.27 1.27)
				)
			)
		)
		(duplicate_pad_numbers_are_jumpers no)
		(fp_line
			(start -0.7874 -0.4064)
			(end 0.7874 -0.4064)
			(stroke
				(width 0.1524)
				(type default)
			)
			(layer "F.SilkS")
		)
		(fp_line
			(start -0.7874 0.4064)
			(end -0.7874 -0.4064)
			(stroke
				(width 0.1524)
				(type default)
			)
			(layer "F.SilkS")
		)
		(fp_line
			(start 0.7874 -0.4064)
			(end 0.7874 0.4064)
			(stroke
				(width 0.1524)
				(type default)
			)
			(layer "F.SilkS")
		)
		(fp_line
			(start 0.7874 0.4064)
			(end -0.7874 0.4064)
			(stroke
				(width 0.1524)
				(type default)
			)
			(layer "F.SilkS")
		)
		(fp_line
			(start -0.67945 -0.305054)
			(end -0.12065 -0.305054)
			(stroke
				(width 0.1)
				(type default)
			)
			(layer "F.Fab")
		)
		(fp_line
			(start -0.67945 0.3048)
			(end -0.67945 -0.305054)
			(stroke
				(width 0.1)
				(type default)
			)
			(layer "F.Fab")
		)
		(fp_line
			(start -0.12065 -0.305054)
			(end -0.12065 -0.2794)
			(stroke
				(width 0.1)
				(type default)
			)
			(layer "F.Fab")
		)
		(fp_line
			(start -0.12065 -0.2794)
			(end 0.12065 -0.2794)
			(stroke
				(width 0.1)
				(type default)
			)
			(layer "F.Fab")
		)
		(fp_line
			(start -0.12065 0.2794)
			(end -0.12065 0.3048)
			(stroke
				(width 0.1)
				(type default)
			)
			(layer "F.Fab")
		)
		(fp_line
			(start -0.12065 0.3048)
			(end -0.67945 0.3048)
			(stroke
				(width 0.1)
				(type default)
			)
			(layer "F.Fab")
		)
		(fp_line
			(start 0.120396 0.2794)
			(end -0.12065 0.2794)
			(stroke
				(width 0.1)
				(type default)
			)
			(layer "F.Fab")
		)
		(fp_line
			(start 0.120396 0.3048)
			(end 0.120396 0.2794)
			(stroke
				(width 0.1)
				(type default)
			)
			(layer "F.Fab")
		)
		(fp_line
			(start 0.12065 -0.3048)
			(end 0.67945 -0.3048)
			(stroke
				(width 0.1)
				(type default)
			)
			(layer "F.Fab")
		)
		(fp_line
			(start 0.12065 -0.2794)
			(end 0.12065 -0.3048)
			(stroke
				(width 0.1)
				(type default)
			)
			(layer "F.Fab")
		)
		(fp_line
			(start 0.67945 -0.3048)
			(end 0.67945 0.3048)
			(stroke
				(width 0.1)
				(type default)
			)
			(layer "F.Fab")
		)
		(fp_line
			(start 0.67945 0.3048)
			(end 0.120396 0.3048)
			(stroke
				(width 0.1)
				(type default)
			)
			(layer "F.Fab")
		)
		(pad "1" smd circle
			(at -0.40005 0)
			(size 0 0)
			(layers "F.Cu" "F.Mask" "F.Paste")
			(net "SSD11_ADC_A0")
		)
		(pad "2" smd circle
			(at 0.40005 0)
			(size 0 0)
			(layers "F.Cu" "F.Mask" "F.Paste")
			(net "SMB_SSD11_ADC_SCL")
		)
	)
	(footprint ""
		(layer "F.Cu")
		(at 330.708 -234.061 -90)
		(property "Reference" "R6147"
			(at 0 0 270)
			(layer "F.SilkS")
			(hide yes)
			(effects
				(font
					(size 1.27 1.27)
				)
			)
		)
		(property "Value" ""
			(at 0 0 270)
			(layer "F.Fab")
			(effects
				(font
					(size 1.27 1.27)
				)
			)
		)
		(duplicate_pad_numbers_are_jumpers no)
		(fp_line
			(start -0.7874 0.4064)
			(end -0.7874 -0.4064)
			(stroke
				(width 0.1524)
				(type default)
			)
			(layer "F.SilkS")
		)
		(fp_line
			(start 0.7874 0.4064)
			(end -0.7874 0.4064)
			(stroke
				(width 0.1524)
				(type default)
			)
			(layer "F.SilkS")
		)
		(fp_line
			(start -0.7874 -0.4064)
			(end 0.7874 -0.4064)
			(stroke
				(width 0.1524)
				(type default)
			)
			(layer "F.SilkS")
		)
		(fp_line
			(start 0.7874 -0.4064)
			(end 0.7874 0.4064)
			(stroke
				(width 0.1524)
				(type default)
			)
			(layer "F.SilkS")
		)
		(fp_line
			(start -0.67945 0.3048)
			(end -0.67945 -0.305054)
			(stroke
				(width 0.1)
				(type default)
			)
			(layer "F.Fab")
		)
		(fp_line
			(start -0.12065 0.3048)
			(end -0.67945 0.3048)
			(stroke
				(width 0.1)
				(type default)
			)
			(layer "F.Fab")
		)
		(fp_line
			(start 0.120396 0.3048)
			(end 0.120396 0.2794)
			(stroke
				(width 0.1)
				(type default)
			)
			(layer "F.Fab")
		)
		(fp_line
			(start 0.67945 0.3048)
			(end 0.120396 0.3048)
			(stroke
				(width 0.1)
				(type default)
			)
			(layer "F.Fab")
		)
		(fp_line
			(start -0.12065 0.2794)
			(end -0.12065 0.3048)
			(stroke
				(width 0.1)
				(type default)
			)
			(layer "F.Fab")
		)
		(fp_line
			(start 0.120396 0.2794)
			(end -0.12065 0.2794)
			(stroke
				(width 0.1)
				(type default)
			)
			(layer "F.Fab")
		)
		(fp_line
			(start -0.12065 -0.2794)
			(end 0.12065 -0.2794)
			(stroke
				(width 0.1)
				(type default)
			)
			(layer "F.Fab")
		)
		(fp_line
			(start 0.12065 -0.2794)
			(end 0.12065 -0.3048)
			(stroke
				(width 0.1)
				(type default)
			)
			(layer "F.Fab")
		)
		(fp_line
			(start 0.12065 -0.3048)
			(end 0.67945 -0.3048)
			(stroke
				(width 0.1)
				(type default)
			)
			(layer "F.Fab")
		)
		(fp_line
			(start 0.67945 -0.3048)
			(end 0.67945 0.3048)
			(stroke
				(width 0.1)
				(type default)
			)
			(layer "F.Fab")
		)
		(fp_line
			(start -0.67945 -0.305054)
			(end -0.12065 -0.305054)
			(stroke
				(width 0.1)
				(type default)
			)
			(layer "F.Fab")
		)
		(fp_line
			(start -0.12065 -0.305054)
			(end -0.12065 -0.2794)
			(stroke
				(width 0.1)
				(type default)
			)
			(layer "F.Fab")
		)
		(pad "1" smd circle
			(at -0.40005 0 270)
			(size 0 0)
			(layers "F.Cu" "F.Mask" "F.Paste")
			(net "PRSNT_GPU_ISO_N")
		)
		(pad "2" smd circle
			(at 0.40005 0 270)
			(size 0 0)
			(layers "F.Cu" "F.Mask" "F.Paste")
			(net "PRSNT_GPU_ISO_R1_N")
		)
	)
	(footprint ""
		(layer "F.Cu")
		(at 240.638838 -276.19325)
		(property "Reference" "R800"
			(at 0 0 0)
			(layer "F.SilkS")
			(hide yes)
			(effects
				(font
					(size 1.27 1.27)
				)
			)
		)
		(property "Value" ""
			(at 0 0 0)
			(layer "F.Fab")
			(effects
				(font
					(size 1.27 1.27)
				)
			)
		)
		(duplicate_pad_numbers_are_jumpers no)
		(fp_line
			(start -0.7874 -0.4064)
			(end 0.7874 -0.4064)
			(stroke
				(width 0.1524)
				(type default)
			)
			(layer "F.SilkS")
		)
		(fp_line
			(start -0.7874 0.4064)
			(end -0.7874 -0.4064)
			(stroke
				(width 0.1524)
				(type default)
			)
			(layer "F.SilkS")
		)
		(fp_line
			(start 0.7874 -0.4064)
			(end 0.7874 0.4064)
			(stroke
				(width 0.1524)
				(type default)
			)
			(layer "F.SilkS")
		)
		(fp_line
			(start 0.7874 0.4064)
			(end -0.7874 0.4064)
			(stroke
				(width 0.1524)
				(type default)
			)
			(layer "F.SilkS")
		)
		(fp_line
			(start -0.67945 -0.305054)
			(end -0.12065 -0.305054)
			(stroke
				(width 0.1)
				(type default)
			)
			(layer "F.Fab")
		)
		(fp_line
			(start -0.67945 0.3048)
			(end -0.67945 -0.305054)
			(stroke
				(width 0.1)
				(type default)
			)
			(layer "F.Fab")
		)
		(fp_line
			(start -0.12065 -0.305054)
			(end -0.12065 -0.2794)
			(stroke
				(width 0.1)
				(type default)
			)
			(layer "F.Fab")
		)
		(fp_line
			(start -0.12065 -0.2794)
			(end 0.12065 -0.2794)
			(stroke
				(width 0.1)
				(type default)
			)
			(layer "F.Fab")
		)
		(fp_line
			(start -0.12065 0.2794)
			(end -0.12065 0.3048)
			(stroke
				(width 0.1)
				(type default)
			)
			(layer "F.Fab")
		)
		(fp_line
			(start -0.12065 0.3048)
			(end -0.67945 0.3048)
			(stroke
				(width 0.1)
				(type default)
			)
			(layer "F.Fab")
		)
		(fp_line
			(start 0.120396 0.2794)
			(end -0.12065 0.2794)
			(stroke
				(width 0.1)
				(type default)
			)
			(layer "F.Fab")
		)
		(fp_line
			(start 0.120396 0.3048)
			(end 0.120396 0.2794)
			(stroke
				(width 0.1)
				(type default)
			)
			(layer "F.Fab")
		)
		(fp_line
			(start 0.12065 -0.3048)
			(end 0.67945 -0.3048)
			(stroke
				(width 0.1)
				(type default)
			)
			(layer "F.Fab")
		)
		(fp_line
			(start 0.12065 -0.2794)
			(end 0.12065 -0.3048)
			(stroke
				(width 0.1)
				(type default)
			)
			(layer "F.Fab")
		)
		(fp_line
			(start 0.67945 -0.3048)
			(end 0.67945 0.3048)
			(stroke
				(width 0.1)
				(type default)
			)
			(layer "F.Fab")
		)
		(fp_line
			(start 0.67945 0.3048)
			(end 0.120396 0.3048)
			(stroke
				(width 0.1)
				(type default)
			)
			(layer "F.Fab")
		)
		(pad "1" smd circle
			(at -0.40005 0)
			(size 0 0)
			(layers "F.Cu" "F.Mask" "F.Paste")
			(net "P1V25_PEX2")
		)
		(pad "2" smd circle
			(at 0.40005 0)
			(size 0 0)
			(layers "F.Cu" "F.Mask" "F.Paste")
			(net "P12V_PEX2_P1V25_VIN_N")
		)
	)
)
